# T6G (Grand Teton) — schematic netlist excerpt (pin names and nets, part order shuffled) for the footprints in the layout excerpt that follows; sources: Cadence DE-HDL packaged netlist, KiCad conversion of 04192023_DAF0TMB3IC0_F0TG_MB_C_brd_V02_OCP.brd

C2294  Q_CAP  22UF 4V 20% X6S  pkg C0402  page 73 : A = PVDDCR_CPU0_P1 ; B = GND
C2350  Q_CAP  22UF 4V 20% X6S  pkg C0402  page 73 : A = PVDDCR_CPU1_P1 ; B = GND

(kicad_pcb
	(version 20260206)
	(generator "pcbnew")
	(generator_version "10.0")
	(general
		(thickness 1.6)
		(legacy_teardrops no)
	)
	(paper "A4")
	(title_block
		(title "04192023_DAF0TMB3IC0_F0TG_MB_C_brd_V02_OCP.brd")
		(comment 1 "Grand Teton / footprints 5888-5889 of 8354")
	)
	(layers
		(0 "F.Cu" signal "TOP")
		(4 "In1.Cu" signal "GND")
		(6 "In2.Cu" signal "IN1")
		(8 "In3.Cu" signal "GND1")
		(10 "In4.Cu" signal "IN2")
		(12 "In5.Cu" signal "GND2")
		(14 "In6.Cu" signal "IN3")
		(16 "In7.Cu" signal "GND3")
		(18 "In8.Cu" signal "VCC")
		(20 "In9.Cu" signal "VCC1")
		(22 "In10.Cu" signal "GND4")
		(24 "In11.Cu" signal "IN4")
		(26 "In12.Cu" signal "GND5")
		(28 "In13.Cu" signal "IN5")
		(30 "In14.Cu" signal "GND6")
		(32 "In15.Cu" signal "IN6")
		(34 "In16.Cu" signal "GND7")
		(2 "B.Cu" signal "BOTTOM")
		(9 "F.Adhes" user "F.Adhesive")
		(11 "B.Adhes" user "B.Adhesive")
		(13 "F.Paste" user "Package Geometry/Pastemask Top")
		(15 "B.Paste" user "Package Geometry/Pastemask Bottom")
		(5 "F.SilkS" user "Ref Des/Silkscreen Top")
		(7 "B.SilkS" user "Ref Des/Silkscreen Bottom")
		(1 "F.Mask" user "Board Geometry/Soldermask Top")
		(3 "B.Mask" user "Board Geometry/Soldermask Bottom")
		(17 "Dwgs.User" user "User.Drawings")
		(19 "Cmts.User" user "User.Comments")
		(21 "Eco1.User" user "User.Eco1")
		(23 "Eco2.User" user "User.Eco2")
		(25 "Edge.Cuts" user "Board Geometry/Outline")
		(27 "Margin" user)
		(31 "F.CrtYd" user "Package Geometry/Place Bound Top")
		(29 "B.CrtYd" user "Package Geometry/Place Bound Bottom")
		(35 "F.Fab" user "Ref Des/Assembly Top")
		(33 "B.Fab" user "Ref Des/Assembly Bottom")
	)
	(footprint ""
		(layer "B.Cu")
		(at 106.621834 -249.368564 180)
		(property "Reference" "C2294"
			(at 0 0 0)
			(layer "B.SilkS")
			(hide yes)
			(effects
				(font
					(size 1.27 1.27)
				)
				(justify mirror)
			)
		)
		(property "Value" ""
			(at 0 0 0)
			(layer "B.Fab")
			(effects
				(font
					(size 1.27 1.27)
				)
				(justify mirror)
			)
		)
		(duplicate_pad_numbers_are_jumpers no)
		(fp_line
			(start 0.7874 0.4064)
			(end 0.7874 -0.4064)
			(stroke
				(width 0.1524)
				(type default)
			)
			(layer "B.SilkS")
		)
		(fp_line
			(start 0.7874 -0.4064)
			(end -0.7874 -0.4064)
			(stroke
				(width 0.1524)
				(type default)
			)
			(layer "B.SilkS")
		)
		(fp_line
			(start -0.7874 0.4064)
			(end 0.7874 0.4064)
			(stroke
				(width 0.1524)
				(type default)
			)
			(layer "B.SilkS")
		)
		(fp_line
			(start -0.7874 -0.4064)
			(end -0.7874 0.4064)
			(stroke
				(width 0.1524)
				(type default)
			)
			(layer "B.SilkS")
		)
		(fp_line
			(start 0.67945 0.3048)
			(end 0.67945 -0.305054)
			(stroke
				(width 0.1)
				(type default)
			)
			(layer "B.Fab")
		)
		(fp_line
			(start 0.67945 -0.305054)
			(end 0.12065 -0.305054)
			(stroke
				(width 0.1)
				(type default)
			)
			(layer "B.Fab")
		)
		(fp_line
			(start 0.12065 0.3048)
			(end 0.67945 0.3048)
			(stroke
				(width 0.1)
				(type default)
			)
			(layer "B.Fab")
		)
		(fp_line
			(start 0.12065 0.2794)
			(end 0.12065 0.3048)
			(stroke
				(width 0.1)
				(type default)
			)
			(layer "B.Fab")
		)
		(fp_line
			(start 0.12065 -0.2794)
			(end -0.12065 -0.2794)
			(stroke
				(width 0.1)
				(type default)
			)
			(layer "B.Fab")
		)
		(fp_line
			(start 0.12065 -0.305054)
			(end 0.12065 -0.2794)
			(stroke
				(width 0.1)
				(type default)
			)
			(layer "B.Fab")
		)
		(fp_line
			(start -0.120396 0.3048)
			(end -0.120396 0.2794)
			(stroke
				(width 0.1)
				(type default)
			)
			(layer "B.Fab")
		)
		(fp_line
			(start -0.120396 0.2794)
			(end 0.12065 0.2794)
			(stroke
				(width 0.1)
				(type default)
			)
			(layer "B.Fab")
		)
		(fp_line
			(start -0.12065 -0.2794)
			(end -0.12065 -0.3048)
			(stroke
				(width 0.1)
				(type default)
			)
			(layer "B.Fab")
		)
		(fp_line
			(start -0.12065 -0.3048)
			(end -0.67945 -0.3048)
			(stroke
				(width 0.1)
				(type default)
			)
			(layer "B.Fab")
		)
		(fp_line
			(start -0.67945 0.3048)
			(end -0.120396 0.3048)
			(stroke
				(width 0.1)
				(type default)
			)
			(layer "B.Fab")
		)
		(fp_line
			(start -0.67945 -0.3048)
			(end -0.67945 0.3048)
			(stroke
				(width 0.1)
				(type default)
			)
			(layer "B.Fab")
		)
		(pad "1" smd circle
			(at 0.40005 0)
			(size 0 0)
			(layers "B.Cu" "B.Mask" "B.Paste")
			(net "PVDDCR_CPU0_P1")
		)
		(pad "2" smd circle
			(at -0.40005 0)
			(size 0 0)
			(layers "B.Cu" "B.Mask" "B.Paste")
			(net "GND")
		)
	)
	(footprint ""
		(layer "B.Cu")
		(at 104.180386 -268.418564)
		(property "Reference" "C2350"
			(at 0 0 0)
			(layer "B.SilkS")
			(hide yes)
			(effects
				(font
					(size 1.27 1.27)
				)
				(justify mirror)
			)
		)
		(property "Value" ""
			(at 0 0 0)
			(layer "B.Fab")
			(effects
				(font
					(size 1.27 1.27)
				)
				(justify mirror)
			)
		)
		(duplicate_pad_numbers_are_jumpers no)
		(fp_line
			(start -0.7874 -0.4064)
			(end -0.7874 0.4064)
			(stroke
				(width 0.1524)
				(type default)
			)
			(layer "B.SilkS")
		)
		(fp_line
			(start -0.7874 0.4064)
			(end 0.7874 0.4064)
			(stroke
				(width 0.1524)
				(type default)
			)
			(layer "B.SilkS")
		)
		(fp_line
			(start 0.7874 -0.4064)
			(end -0.7874 -0.4064)
			(stroke
				(width 0.1524)
				(type default)
			)
			(layer "B.SilkS")
		)
		(fp_line
			(start 0.7874 0.4064)
			(end 0.7874 -0.4064)
			(stroke
				(width 0.1524)
				(type default)
			)
			(layer "B.SilkS")
		)
		(fp_line
			(start -0.67945 -0.3048)
			(end -0.67945 0.3048)
			(stroke
				(width 0.1)
				(type default)
			)
			(layer "B.Fab")
		)
		(fp_line
			(start -0.67945 0.3048)
			(end -0.120396 0.3048)
			(stroke
				(width 0.1)
				(type default)
			)
			(layer "B.Fab")
		)
		(fp_line
			(start -0.12065 -0.3048)
			(end -0.67945 -0.3048)
			(stroke
				(width 0.1)
				(type default)
			)
			(layer "B.Fab")
		)
		(fp_line
			(start -0.12065 -0.2794)
			(end -0.12065 -0.3048)
			(stroke
				(width 0.1)
				(type default)
			)
			(layer "B.Fab")
		)
		(fp_line
			(start -0.120396 0.2794)
			(end 0.12065 0.2794)
			(stroke
				(width 0.1)
				(type default)
			)
			(layer "B.Fab")
		)
		(fp_line
			(start -0.120396 0.3048)
			(end -0.120396 0.2794)
			(stroke
				(width 0.1)
				(type default)
			)
			(layer "B.Fab")
		)
		(fp_line
			(start 0.12065 -0.305054)
			(end 0.12065 -0.2794)
			(stroke
				(width 0.1)
				(type default)
			)
			(layer "B.Fab")
		)
		(fp_line
			(start 0.12065 -0.2794)
			(end -0.12065 -0.2794)
			(stroke
				(width 0.1)
				(type default)
			)
			(layer "B.Fab")
		)
		(fp_line
			(start 0.12065 0.2794)
			(end 0.12065 0.3048)
			(stroke
				(width 0.1)
				(type default)
			)
			(layer "B.Fab")
		)
		(fp_line
			(start 0.12065 0.3048)
			(end 0.67945 0.3048)
			(stroke
				(width 0.1)
				(type default)
			)
			(layer "B.Fab")
		)
		(fp_line
			(start 0.67945 -0.305054)
			(end 0.12065 -0.305054)
			(stroke
				(width 0.1)
				(type default)
			)
			(layer "B.Fab")
		)
		(fp_line
			(start 0.67945 0.3048)
			(end 0.67945 -0.305054)
			(stroke
				(width 0.1)
				(type default)
			)
			(layer "B.Fab")
		)
		(pad "1" smd circle
			(at 0.40005 0 180)
			(size 0 0)
			(layers "B.Cu" "B.Mask" "B.Paste")
			(net "PVDDCR_CPU1_P1")
		)
		(pad "2" smd circle
			(at -0.40005 0 180)
			(size 0 0)
			(layers "B.Cu" "B.Mask" "B.Paste")
			(net "GND")
		)
	)
)
